# T6G (Grand Teton) — schematic netlist excerpt (pin names and nets, part order shuffled) for the footprints in the layout excerpt that follows; sources: Cadence DE-HDL packaged netlist, KiCad conversion of 04192023_DAF0TMB3IC0_F0TG_MB_C_brd_V02_OCP.brd

C384  Q_CAP  1UF 4V 20% X6S  pkg 0201  page 345 : A = P0V9_CPU1_RT2_2A ; B = GND
C2301  Q_CAP  22UF 4V 20% X6S  pkg C0402  page 73 : A = PVDDCR_CPU0_P1 ; B = GND
C6109  Q_CAP  1PF 50V 0.05P COG  pkg C0402  page 179 : A = P1V2_CPU0_USB2_DVDD12 ; B = GND

(kicad_pcb
	(version 20260206)
	(generator "pcbnew")
	(generator_version "10.0")
	(general
		(thickness 1.6)
		(legacy_teardrops no)
	)
	(paper "A4")
	(title_block
		(title "04192023_DAF0TMB3IC0_F0TG_MB_C_brd_V02_OCP.brd")
		(comment 1 "Grand Teton / footprints 7453-7455 of 8354")
	)
	(layers
		(0 "F.Cu" signal "TOP")
		(4 "In1.Cu" signal "GND")
		(6 "In2.Cu" signal "IN1")
		(8 "In3.Cu" signal "GND1")
		(10 "In4.Cu" signal "IN2")
		(12 "In5.Cu" signal "GND2")
		(14 "In6.Cu" signal "IN3")
		(16 "In7.Cu" signal "GND3")
		(18 "In8.Cu" signal "VCC")
		(20 "In9.Cu" signal "VCC1")
		(22 "In10.Cu" signal "GND4")
		(24 "In11.Cu" signal "IN4")
		(26 "In12.Cu" signal "GND5")
		(28 "In13.Cu" signal "IN5")
		(30 "In14.Cu" signal "GND6")
		(32 "In15.Cu" signal "IN6")
		(34 "In16.Cu" signal "GND7")
		(2 "B.Cu" signal "BOTTOM")
		(9 "F.Adhes" user "F.Adhesive")
		(11 "B.Adhes" user "B.Adhesive")
		(13 "F.Paste" user "Package Geometry/Pastemask Top")
		(15 "B.Paste" user "Package Geometry/Pastemask Bottom")
		(5 "F.SilkS" user "Ref Des/Silkscreen Top")
		(7 "B.SilkS" user "Ref Des/Silkscreen Bottom")
		(1 "F.Mask" user "Board Geometry/Soldermask Top")
		(3 "B.Mask" user "Board Geometry/Soldermask Bottom")
		(17 "Dwgs.User" user "User.Drawings")
		(19 "Cmts.User" user "User.Comments")
		(21 "Eco1.User" user "User.Eco1")
		(23 "Eco2.User" user "User.Eco2")
		(25 "Edge.Cuts" user "Board Geometry/Outline")
		(27 "Margin" user)
		(31 "F.CrtYd" user "Package Geometry/Place Bound Top")
		(29 "B.CrtYd" user "Package Geometry/Place Bound Bottom")
		(35 "F.Fab" user "Ref Des/Assembly Top")
		(33 "B.Fab" user "Ref Des/Assembly Bottom")
	)
	(footprint ""
		(layer "B.Cu")
		(at 108.50626 -35.088068 90)
		(property "Reference" "C6109"
			(at 0 0 90)
			(layer "B.SilkS")
			(hide yes)
			(effects
				(font
					(size 1.27 1.27)
				)
				(justify mirror)
			)
		)
		(property "Value" ""
			(at 0 0 90)
			(layer "B.Fab")
			(effects
				(font
					(size 1.27 1.27)
				)
				(justify mirror)
			)
		)
		(duplicate_pad_numbers_are_jumpers no)
		(fp_line
			(start 0.7874 -0.4064)
			(end -0.7874 -0.4064)
			(stroke
				(width 0.1524)
				(type default)
			)
			(layer "B.SilkS")
		)
		(fp_line
			(start -0.7874 -0.4064)
			(end -0.7874 0.4064)
			(stroke
				(width 0.1524)
				(type default)
			)
			(layer "B.SilkS")
		)
		(fp_line
			(start 0.7874 0.4064)
			(end 0.7874 -0.4064)
			(stroke
				(width 0.1524)
				(type default)
			)
			(layer "B.SilkS")
		)
		(fp_line
			(start -0.7874 0.4064)
			(end 0.7874 0.4064)
			(stroke
				(width 0.1524)
				(type default)
			)
			(layer "B.SilkS")
		)
		(fp_line
			(start 0.67945 -0.305054)
			(end 0.12065 -0.305054)
			(stroke
				(width 0.1)
				(type default)
			)
			(layer "B.Fab")
		)
		(fp_line
			(start 0.12065 -0.305054)
			(end 0.12065 -0.2794)
			(stroke
				(width 0.1)
				(type default)
			)
			(layer "B.Fab")
		)
		(fp_line
			(start -0.12065 -0.3048)
			(end -0.67945 -0.3048)
			(stroke
				(width 0.1)
				(type default)
			)
			(layer "B.Fab")
		)
		(fp_line
			(start -0.67945 -0.3048)
			(end -0.67945 0.3048)
			(stroke
				(width 0.1)
				(type default)
			)
			(layer "B.Fab")
		)
		(fp_line
			(start 0.12065 -0.2794)
			(end -0.12065 -0.2794)
			(stroke
				(width 0.1)
				(type default)
			)
			(layer "B.Fab")
		)
		(fp_line
			(start -0.12065 -0.2794)
			(end -0.12065 -0.3048)
			(stroke
				(width 0.1)
				(type default)
			)
			(layer "B.Fab")
		)
		(fp_line
			(start 0.12065 0.2794)
			(end 0.12065 0.3048)
			(stroke
				(width 0.1)
				(type default)
			)
			(layer "B.Fab")
		)
		(fp_line
			(start -0.120396 0.2794)
			(end 0.12065 0.2794)
			(stroke
				(width 0.1)
				(type default)
			)
			(layer "B.Fab")
		)
		(fp_line
			(start 0.67945 0.3048)
			(end 0.67945 -0.305054)
			(stroke
				(width 0.1)
				(type default)
			)
			(layer "B.Fab")
		)
		(fp_line
			(start 0.12065 0.3048)
			(end 0.67945 0.3048)
			(stroke
				(width 0.1)
				(type default)
			)
			(layer "B.Fab")
		)
		(fp_line
			(start -0.120396 0.3048)
			(end -0.120396 0.2794)
			(stroke
				(width 0.1)
				(type default)
			)
			(layer "B.Fab")
		)
		(fp_line
			(start -0.67945 0.3048)
			(end -0.120396 0.3048)
			(stroke
				(width 0.1)
				(type default)
			)
			(layer "B.Fab")
		)
		(pad "1" smd circle
			(at 0.40005 0 270)
			(size 0 0)
			(layers "B.Cu" "B.Mask" "B.Paste")
			(net "P1V2_CPU0_USB2_DVDD12")
		)
		(pad "2" smd circle
			(at -0.40005 0 270)
			(size 0 0)
			(layers "B.Cu" "B.Mask" "B.Paste")
			(net "GND")
		)
	)
	(footprint ""
		(layer "B.Cu")
		(at 145.046192 -387.05028)
		(property "Reference" "C384"
			(at 0 0 0)
			(layer "B.SilkS")
			(hide yes)
			(effects
				(font
					(size 1.27 1.27)
				)
				(justify mirror)
			)
		)
		(property "Value" ""
			(at 0 0 0)
			(layer "B.Fab")
			(effects
				(font
					(size 1.27 1.27)
				)
				(justify mirror)
			)
		)
		(duplicate_pad_numbers_are_jumpers no)
		(fp_line
			(start -0.299974 -0.150114)
			(end -0.299974 0.150114)
			(stroke
				(width 0.1)
				(type default)
			)
			(layer "B.Fab")
		)
		(fp_line
			(start -0.299974 0.150114)
			(end 0.299974 0.150114)
			(stroke
				(width 0.1)
				(type default)
			)
			(layer "B.Fab")
		)
		(fp_line
			(start 0.299974 -0.150114)
			(end -0.299974 -0.150114)
			(stroke
				(width 0.1)
				(type default)
			)
			(layer "B.Fab")
		)
		(fp_line
			(start 0.299974 0.150114)
			(end 0.299974 -0.150114)
			(stroke
				(width 0.1)
				(type default)
			)
			(layer "B.Fab")
		)
		(pad "1" smd rect
			(at 0.2667 0 180)
			(size 0.3048 0.381)
			(layers "B.Cu" "B.Mask" "B.Paste")
			(net "P0V9_CPU1_RT2_2A")
		)
		(pad "2" smd rect
			(at -0.2667 0 180)
			(size 0.3048 0.381)
			(layers "B.Cu" "B.Mask" "B.Paste")
			(net "GND")
		)
	)
	(footprint ""
		(layer "B.Cu")
		(at 108.145834 -250.257564)
		(property "Reference" "C2301"
			(at 0 0 0)
			(layer "B.SilkS")
			(hide yes)
			(effects
				(font
					(size 1.27 1.27)
				)
				(justify mirror)
			)
		)
		(property "Value" ""
			(at 0 0 0)
			(layer "B.Fab")
			(effects
				(font
					(size 1.27 1.27)
				)
				(justify mirror)
			)
		)
		(duplicate_pad_numbers_are_jumpers no)
		(fp_line
			(start -0.7874 -0.4064)
			(end -0.7874 0.4064)
			(stroke
				(width 0.1524)
				(type default)
			)
			(layer "B.SilkS")
		)
		(fp_line
			(start -0.7874 0.4064)
			(end 0.7874 0.4064)
			(stroke
				(width 0.1524)
				(type default)
			)
			(layer "B.SilkS")
		)
		(fp_line
			(start 0.7874 -0.4064)
			(end -0.7874 -0.4064)
			(stroke
				(width 0.1524)
				(type default)
			)
			(layer "B.SilkS")
		)
		(fp_line
			(start 0.7874 0.4064)
			(end 0.7874 -0.4064)
			(stroke
				(width 0.1524)
				(type default)
			)
			(layer "B.SilkS")
		)
		(fp_line
			(start -0.67945 -0.3048)
			(end -0.67945 0.3048)
			(stroke
				(width 0.1)
				(type default)
			)
			(layer "B.Fab")
		)
		(fp_line
			(start -0.67945 0.3048)
			(end -0.120396 0.3048)
			(stroke
				(width 0.1)
				(type default)
			)
			(layer "B.Fab")
		)
		(fp_line
			(start -0.12065 -0.3048)
			(end -0.67945 -0.3048)
			(stroke
				(width 0.1)
				(type default)
			)
			(layer "B.Fab")
		)
		(fp_line
			(start -0.12065 -0.2794)
			(end -0.12065 -0.3048)
			(stroke
				(width 0.1)
				(type default)
			)
			(layer "B.Fab")
		)
		(fp_line
			(start -0.120396 0.2794)
			(end 0.12065 0.2794)
			(stroke
				(width 0.1)
				(type default)
			)
			(layer "B.Fab")
		)
		(fp_line
			(start -0.120396 0.3048)
			(end -0.120396 0.2794)
			(stroke
				(width 0.1)
				(type default)
			)
			(layer "B.Fab")
		)
		(fp_line
			(start 0.12065 -0.305054)
			(end 0.12065 -0.2794)
			(stroke
				(width 0.1)
				(type default)
			)
			(layer "B.Fab")
		)
		(fp_line
			(start 0.12065 -0.2794)
			(end -0.12065 -0.2794)
			(stroke
				(width 0.1)
				(type default)
			)
			(layer "B.Fab")
		)
		(fp_line
			(start 0.12065 0.2794)
			(end 0.12065 0.3048)
			(stroke
				(width 0.1)
				(type default)
			)
			(layer "B.Fab")
		)
		(fp_line
			(start 0.12065 0.3048)
			(end 0.67945 0.3048)
			(stroke
				(width 0.1)
				(type default)
			)
			(layer "B.Fab")
		)
		(fp_line
			(start 0.67945 -0.305054)
			(end 0.12065 -0.305054)
			(stroke
				(width 0.1)
				(type default)
			)
			(layer "B.Fab")
		)
		(fp_line
			(start 0.67945 0.3048)
			(end 0.67945 -0.305054)
			(stroke
				(width 0.1)
				(type default)
			)
			(layer "B.Fab")
		)
		(pad "1" smd circle
			(at 0.40005 0 180)
			(size 0 0)
			(layers "B.Cu" "B.Mask" "B.Paste")
			(net "PVDDCR_CPU0_P1")
		)
		(pad "2" smd circle
			(at -0.40005 0 180)
			(size 0 0)
			(layers "B.Cu" "B.Mask" "B.Paste")
			(net "GND")
		)
	)
)
